(kicad_pcb
	(version 20260206)
	(generator "pcbnew")
	(generator_version "10.0")
	(general
		(thickness 1.6)
		(legacy_teardrops no)
	)
	(paper "A4")
	(title_block
		(title "04192023_DAF0TMB3IC0_F0TG_MB_C_brd_V02_OCP.brd")
		(comment 1 "Grand Teton / footprints 5666-5672 of 8354")
	)
	(layers
		(0 "F.Cu" signal "TOP")
		(4 "In1.Cu" signal "GND")
		(6 "In2.Cu" signal "IN1")
		(8 "In3.Cu" signal "GND1")
		(10 "In4.Cu" signal "IN2")
		(12 "In5.Cu" signal "GND2")
		(14 "In6.Cu" signal "IN3")
		(16 "In7.Cu" signal "GND3")
		(18 "In8.Cu" signal "VCC")
		(20 "In9.Cu" signal "VCC1")
		(22 "In10.Cu" signal "GND4")
		(24 "In11.Cu" signal "IN4")
		(26 "In12.Cu" signal "GND5")
		(28 "In13.Cu" signal "IN5")
		(30 "In14.Cu" signal "GND6")
		(32 "In15.Cu" signal "IN6")
		(34 "In16.Cu" signal "GND7")
		(2 "B.Cu" signal "BOTTOM")
		(9 "F.Adhes" user "F.Adhesive")
		(11 "B.Adhes" user "B.Adhesive")
		(13 "F.Paste" user "Package Geometry/Pastemask Top")
		(15 "B.Paste" user "Package Geometry/Pastemask Bottom")
		(5 "F.SilkS" user "Ref Des/Silkscreen Top")
		(7 "B.SilkS" user "Ref Des/Silkscreen Bottom")
		(1 "F.Mask" user "Board Geometry/Soldermask Top")
		(3 "B.Mask" user "Board Geometry/Soldermask Bottom")
		(17 "Dwgs.User" user "User.Drawings")
		(19 "Cmts.User" user "User.Comments")
		(21 "Eco1.User" user "User.Eco1")
		(23 "Eco2.User" user "User.Eco2")
		(25 "Edge.Cuts" user "Board Geometry/Outline")
		(27 "Margin" user)
		(31 "F.CrtYd" user "Package Geometry/Place Bound Top")
		(29 "B.CrtYd" user "Package Geometry/Place Bound Bottom")
		(35 "F.Fab" user "Ref Des/Assembly Top")
		(33 "B.Fab" user "Ref Des/Assembly Bottom")
	)
	(footprint ""
		(layer "B.Cu")
		(at 24.890476 -337.985354 -90)
		(property "Reference" "PC634_4"
			(at 0 0 90)
			(layer "B.SilkS")
			(hide yes)
			(effects
				(font
					(size 1.27 1.27)
				)
				(justify mirror)
			)
		)
		(property "Value" ""
			(at 0 0 90)
			(layer "B.Fab")
			(effects
				(font
					(size 1.27 1.27)
				)
				(justify mirror)
			)
		)
		(duplicate_pad_numbers_are_jumpers no)
		(fp_line
			(start -1.524 0.762)
			(end 1.524 0.762)
			(stroke
				(width 0.1524)
				(type default)
			)
			(layer "B.SilkS")
		)
		(fp_line
			(start 1.524 0.762)
			(end 1.524 -0.762)
			(stroke
				(width 0.1524)
				(type default)
			)
			(layer "B.SilkS")
		)
		(fp_line
			(start -1.524 -0.762)
			(end -1.524 0.762)
			(stroke
				(width 0.1524)
				(type default)
			)
			(layer "B.SilkS")
		)
		(fp_line
			(start 1.524 -0.762)
			(end -1.524 -0.762)
			(stroke
				(width 0.1524)
				(type default)
			)
			(layer "B.SilkS")
		)
		(fp_line
			(start -1.1049 0.724916)
			(end -1.1049 -0.724916)
			(stroke
				(width 0.1)
				(type default)
			)
			(layer "B.Fab")
		)
		(fp_line
			(start 1.1049 0.724916)
			(end -1.1049 0.724916)
			(stroke
				(width 0.1)
				(type default)
			)
			(layer "B.Fab")
		)
		(fp_line
			(start -1.1049 -0.724916)
			(end 1.1049 -0.724916)
			(stroke
				(width 0.1)
				(type default)
			)
			(layer "B.Fab")
		)
		(fp_line
			(start 1.1049 -0.724916)
			(end 1.1049 0.724916)
			(stroke
				(width 0.1)
				(type default)
			)
			(layer "B.Fab")
		)
		(pad "1" smd rect
			(at 0.889 0 270)
			(size 1.016 1.27)
			(layers "B.Cu" "B.Mask" "B.Paste")
			(net "PVDDIO_P1")
		)
		(pad "2" smd rect
			(at -0.889 0 270)
			(size 1.016 1.27)
			(layers "B.Cu" "B.Mask" "B.Paste")
			(net "GND")
		)
	)
	(footprint ""
		(layer "B.Cu")
		(at 152.849834 -322.903342 -90)
		(property "Reference" "R730"
			(at 0 0 90)
			(layer "B.SilkS")
			(hide yes)
			(effects
				(font
					(size 1.27 1.27)
				)
				(justify mirror)
			)
		)
		(property "Value" ""
			(at 0 0 90)
			(layer "B.Fab")
			(effects
				(font
					(size 1.27 1.27)
				)
				(justify mirror)
			)
		)
		(duplicate_pad_numbers_are_jumpers no)
		(fp_line
			(start -0.7874 0.4064)
			(end 0.7874 0.4064)
			(stroke
				(width 0.1524)
				(type default)
			)
			(layer "B.SilkS")
		)
		(fp_line
			(start 0.7874 0.4064)
			(end 0.7874 -0.4064)
			(stroke
				(width 0.1524)
				(type default)
			)
			(layer "B.SilkS")
		)
		(fp_line
			(start -0.7874 -0.4064)
			(end -0.7874 0.4064)
			(stroke
				(width 0.1524)
				(type default)
			)
			(layer "B.SilkS")
		)
		(fp_line
			(start 0.7874 -0.4064)
			(end -0.7874 -0.4064)
			(stroke
				(width 0.1524)
				(type default)
			)
			(layer "B.SilkS")
		)
		(fp_line
			(start -0.67945 0.3048)
			(end -0.120396 0.3048)
			(stroke
				(width 0.1)
				(type default)
			)
			(layer "B.Fab")
		)
		(fp_line
			(start -0.120396 0.3048)
			(end -0.120396 0.2794)
			(stroke
				(width 0.1)
				(type default)
			)
			(layer "B.Fab")
		)
		(fp_line
			(start 0.12065 0.3048)
			(end 0.67945 0.3048)
			(stroke
				(width 0.1)
				(type default)
			)
			(layer "B.Fab")
		)
		(fp_line
			(start 0.67945 0.3048)
			(end 0.67945 -0.305054)
			(stroke
				(width 0.1)
				(type default)
			)
			(layer "B.Fab")
		)
		(fp_line
			(start -0.120396 0.2794)
			(end 0.12065 0.2794)
			(stroke
				(width 0.1)
				(type default)
			)
			(layer "B.Fab")
		)
		(fp_line
			(start 0.12065 0.2794)
			(end 0.12065 0.3048)
			(stroke
				(width 0.1)
				(type default)
			)
			(layer "B.Fab")
		)
		(fp_line
			(start -0.12065 -0.2794)
			(end -0.12065 -0.3048)
			(stroke
				(width 0.1)
				(type default)
			)
			(layer "B.Fab")
		)
		(fp_line
			(start 0.12065 -0.2794)
			(end -0.12065 -0.2794)
			(stroke
				(width 0.1)
				(type default)
			)
			(layer "B.Fab")
		)
		(fp_line
			(start -0.67945 -0.3048)
			(end -0.67945 0.3048)
			(stroke
				(width 0.1)
				(type default)
			)
			(layer "B.Fab")
		)
		(fp_line
			(start -0.12065 -0.3048)
			(end -0.67945 -0.3048)
			(stroke
				(width 0.1)
				(type default)
			)
			(layer "B.Fab")
		)
		(fp_line
			(start 0.12065 -0.305054)
			(end 0.12065 -0.2794)
			(stroke
				(width 0.1)
				(type default)
			)
			(layer "B.Fab")
		)
		(fp_line
			(start 0.67945 -0.305054)
			(end 0.12065 -0.305054)
			(stroke
				(width 0.1)
				(type default)
			)
			(layer "B.Fab")
		)
		(pad "1" smd circle
			(at 0.40005 0 90)
			(size 0 0)
			(layers "B.Cu" "B.Mask" "B.Paste")
			(net "PVDD18_S5_P1")
		)
		(pad "2" smd circle
			(at -0.40005 0 90)
			(size 0 0)
			(layers "B.Cu" "B.Mask" "B.Paste")
			(net "SPI_CPU1_CLK")
		)
	)
	(footprint ""
		(layer "B.Cu")
		(at 350.03867 -160.080198 90)
		(property "Reference" "PR430"
			(at 0 0 90)
			(layer "B.SilkS")
			(hide yes)
			(effects
				(font
					(size 1.27 1.27)
				)
				(justify mirror)
			)
		)
		(property "Value" ""
			(at 0 0 90)
			(layer "B.Fab")
			(effects
				(font
					(size 1.27 1.27)
				)
				(justify mirror)
			)
		)
		(duplicate_pad_numbers_are_jumpers no)
		(fp_line
			(start 0.7874 -0.4064)
			(end -0.7874 -0.4064)
			(stroke
				(width 0.1524)
				(type default)
			)
			(layer "B.SilkS")
		)
		(fp_line
			(start -0.7874 -0.4064)
			(end -0.7874 0.4064)
			(stroke
				(width 0.1524)
				(type default)
			)
			(layer "B.SilkS")
		)
		(fp_line
			(start 0.7874 0.4064)
			(end 0.7874 -0.4064)
			(stroke
				(width 0.1524)
				(type default)
			)
			(layer "B.SilkS")
		)
		(fp_line
			(start -0.7874 0.4064)
			(end 0.7874 0.4064)
			(stroke
				(width 0.1524)
				(type default)
			)
			(layer "B.SilkS")
		)
		(fp_line
			(start 0.67945 -0.305054)
			(end 0.12065 -0.305054)
			(stroke
				(width 0.1)
				(type default)
			)
			(layer "B.Fab")
		)
		(fp_line
			(start 0.12065 -0.305054)
			(end 0.12065 -0.2794)
			(stroke
				(width 0.1)
				(type default)
			)
			(layer "B.Fab")
		)
		(fp_line
			(start -0.12065 -0.3048)
			(end -0.67945 -0.3048)
			(stroke
				(width 0.1)
				(type default)
			)
			(layer "B.Fab")
		)
		(fp_line
			(start -0.67945 -0.3048)
			(end -0.67945 0.3048)
			(stroke
				(width 0.1)
				(type default)
			)
			(layer "B.Fab")
		)
		(fp_line
			(start 0.12065 -0.2794)
			(end -0.12065 -0.2794)
			(stroke
				(width 0.1)
				(type default)
			)
			(layer "B.Fab")
		)
		(fp_line
			(start -0.12065 -0.2794)
			(end -0.12065 -0.3048)
			(stroke
				(width 0.1)
				(type default)
			)
			(layer "B.Fab")
		)
		(fp_line
			(start 0.12065 0.2794)
			(end 0.12065 0.3048)
			(stroke
				(width 0.1)
				(type default)
			)
			(layer "B.Fab")
		)
		(fp_line
			(start -0.120396 0.2794)
			(end 0.12065 0.2794)
			(stroke
				(width 0.1)
				(type default)
			)
			(layer "B.Fab")
		)
		(fp_line
			(start 0.67945 0.3048)
			(end 0.67945 -0.305054)
			(stroke
				(width 0.1)
				(type default)
			)
			(layer "B.Fab")
		)
		(fp_line
			(start 0.12065 0.3048)
			(end 0.67945 0.3048)
			(stroke
				(width 0.1)
				(type default)
			)
			(layer "B.Fab")
		)
		(fp_line
			(start -0.120396 0.3048)
			(end -0.120396 0.2794)
			(stroke
				(width 0.1)
				(type default)
			)
			(layer "B.Fab")
		)
		(fp_line
			(start -0.67945 0.3048)
			(end -0.120396 0.3048)
			(stroke
				(width 0.1)
				(type default)
			)
			(layer "B.Fab")
		)
		(pad "1" smd circle
			(at 0.40005 0 270)
			(size 0 0)
			(layers "B.Cu" "B.Mask" "B.Paste")
			(net "PVDDCR_CPU0_P0_PVCC")
		)
		(pad "2" smd circle
			(at -0.40005 0 270)
			(size 0 0)
			(layers "B.Cu" "B.Mask" "B.Paste")
			(net "PVDDCR_CPU0_P0_VCC6")
		)
	)
	(footprint ""
		(layer "B.Cu")
		(at 198.438008 -111.380016)
		(property "Reference" "R224"
			(at 0 0 0)
			(layer "B.SilkS")
			(hide yes)
			(effects
				(font
					(size 1.27 1.27)
				)
				(justify mirror)
			)
		)
		(property "Value" ""
			(at 0 0 0)
			(layer "B.Fab")
			(effects
				(font
					(size 1.27 1.27)
				)
				(justify mirror)
			)
		)
		(duplicate_pad_numbers_are_jumpers no)
		(fp_line
			(start -0.7874 -0.4064)
			(end -0.7874 0.4064)
			(stroke
				(width 0.1524)
				(type default)
			)
			(layer "B.SilkS")
		)
		(fp_line
			(start -0.7874 0.4064)
			(end 0.7874 0.4064)
			(stroke
				(width 0.1524)
				(type default)
			)
			(layer "B.SilkS")
		)
		(fp_line
			(start 0.7874 -0.4064)
			(end -0.7874 -0.4064)
			(stroke
				(width 0.1524)
				(type default)
			)
			(layer "B.SilkS")
		)
		(fp_line
			(start 0.7874 0.4064)
			(end 0.7874 -0.4064)
			(stroke
				(width 0.1524)
				(type default)
			)
			(layer "B.SilkS")
		)
		(fp_line
			(start -0.67945 -0.3048)
			(end -0.67945 0.3048)
			(stroke
				(width 0.1)
				(type default)
			)
			(layer "B.Fab")
		)
		(fp_line
			(start -0.67945 0.3048)
			(end -0.120396 0.3048)
			(stroke
				(width 0.1)
				(type default)
			)
			(layer "B.Fab")
		)
		(fp_line
			(start -0.12065 -0.3048)
			(end -0.67945 -0.3048)
			(stroke
				(width 0.1)
				(type default)
			)
			(layer "B.Fab")
		)
		(fp_line
			(start -0.12065 -0.2794)
			(end -0.12065 -0.3048)
			(stroke
				(width 0.1)
				(type default)
			)
			(layer "B.Fab")
		)
		(fp_line
			(start -0.120396 0.2794)
			(end 0.12065 0.2794)
			(stroke
				(width 0.1)
				(type default)
			)
			(layer "B.Fab")
		)
		(fp_line
			(start -0.120396 0.3048)
			(end -0.120396 0.2794)
			(stroke
				(width 0.1)
				(type default)
			)
			(layer "B.Fab")
		)
		(fp_line
			(start 0.12065 -0.305054)
			(end 0.12065 -0.2794)
			(stroke
				(width 0.1)
				(type default)
			)
			(layer "B.Fab")
		)
		(fp_line
			(start 0.12065 -0.2794)
			(end -0.12065 -0.2794)
			(stroke
				(width 0.1)
				(type default)
			)
			(layer "B.Fab")
		)
		(fp_line
			(start 0.12065 0.2794)
			(end 0.12065 0.3048)
			(stroke
				(width 0.1)
				(type default)
			)
			(layer "B.Fab")
		)
		(fp_line
			(start 0.12065 0.3048)
			(end 0.67945 0.3048)
			(stroke
				(width 0.1)
				(type default)
			)
			(layer "B.Fab")
		)
		(fp_line
			(start 0.67945 -0.305054)
			(end 0.12065 -0.305054)
			(stroke
				(width 0.1)
				(type default)
			)
			(layer "B.Fab")
		)
		(fp_line
			(start 0.67945 0.3048)
			(end 0.67945 -0.305054)
			(stroke
				(width 0.1)
				(type default)
			)
			(layer "B.Fab")
		)
		(pad "1" smd circle
			(at 0.40005 0 180)
			(size 0 0)
			(layers "B.Cu" "B.Mask" "B.Paste")
			(net "PVDD33_S5_EN")
		)
		(pad "2" smd circle
			(at -0.40005 0 180)
			(size 0 0)
			(layers "B.Cu" "B.Mask" "B.Paste")
			(net "FM_PVDD33_S5_EN")
		)
	)
	(footprint ""
		(layer "B.Cu")
		(at 48.65624 -429.114966)
		(property "Reference" "Q107"
			(at 1.138682 -2.10185 0)
			(unlocked yes)
			(layer "B.SilkS")
			(effects
				(font
					(size 0.7874 0.5842)
					(thickness 0.1524)
				)
				(justify left mirror)
			)
		)
		(property "Value" ""
			(at 0 0 0)
			(layer "B.Fab")
			(effects
				(font
					(size 1.27 1.27)
				)
				(justify mirror)
			)
		)
		(duplicate_pad_numbers_are_jumpers no)
		(fp_line
			(start -1.332738 -1.100074)
			(end -1.332738 1.100074)
			(stroke
				(width 0.1524)
				(type default)
			)
			(layer "B.SilkS")
		)
		(fp_line
			(start -1.332738 1.100074)
			(end 1.332738 1.100074)
			(stroke
				(width 0.1524)
				(type default)
			)
			(layer "B.SilkS")
		)
		(fp_line
			(start -0.4826 -1.100074)
			(end -1.332738 -1.100074)
			(stroke
				(width 0.1524)
				(type default)
			)
			(layer "B.SilkS")
		)
		(fp_line
			(start 0 -0.541274)
			(end -0.4826 -1.100074)
			(stroke
				(width 0.1524)
				(type default)
			)
			(layer "B.SilkS")
		)
		(fp_line
			(start 0.4826 -1.100074)
			(end 0 -0.541274)
			(stroke
				(width 0.1524)
				(type default)
			)
			(layer "B.SilkS")
		)
		(fp_line
			(start 1.332738 -1.100074)
			(end 0.4826 -1.100074)
			(stroke
				(width 0.1524)
				(type default)
			)
			(layer "B.SilkS")
		)
		(fp_line
			(start 1.332738 1.100074)
			(end 1.332738 -1.100074)
			(stroke
				(width 0.1524)
				(type default)
			)
			(layer "B.SilkS")
		)
		(fp_poly
			(pts
				(xy 1.668272 -0.896112) (xy 2.452878 -0.870458) (xy 2.159508 -1.508252)
			)
			(stroke
				(width 0)
				(type default)
			)
			(fill yes)
			(layer "B.SilkS")
		)
		(fp_line
			(start -0.674878 -1.100074)
			(end -0.674878 1.100074)
			(stroke
				(width 0.1)
				(type default)
			)
			(layer "B.Fab")
		)
		(fp_line
			(start -0.674878 1.100074)
			(end 0.674878 1.100074)
			(stroke
				(width 0.1)
				(type default)
			)
			(layer "B.Fab")
		)
		(fp_line
			(start 0.674878 -1.100074)
			(end -0.674878 -1.100074)
			(stroke
				(width 0.1)
				(type default)
			)
			(layer "B.Fab")
		)
		(fp_line
			(start 0.674878 1.100074)
			(end 0.674878 -1.100074)
			(stroke
				(width 0.1)
				(type default)
			)
			(layer "B.Fab")
		)
		(fp_poly
			(pts
				(xy 2.2352 -0.298958) (xy 2.2352 -1.001014) (xy 1.533144 -0.649986)
			)
			(stroke
				(width 0)
				(type default)
			)
			(fill yes)
			(layer "B.Fab")
		)
		(pad "1" smd rect
			(at 0.94996 -0.649986 90)
			(size 0.4318 0.508)
			(layers "B.Cu" "B.Mask" "B.Paste")
			(net "GND")
		)
		(pad "2" smd rect
			(at 0.94996 0 90)
			(size 0.4318 0.508)
			(layers "B.Cu" "B.Mask" "B.Paste")
			(net "GPU_PRSNT_N")
		)
		(pad "3" smd rect
			(at 0.94996 0.649986 90)
			(size 0.4318 0.508)
			(layers "B.Cu" "B.Mask" "B.Paste")
			(net "GPU_PRSNT_N_ISO")
		)
		(pad "4" smd rect
			(at -0.94996 0.649986 90)
			(size 0.4318 0.508)
			(layers "B.Cu" "B.Mask" "B.Paste")
			(net "GND")
		)
		(pad "5" smd rect
			(at -0.94996 0 90)
			(size 0.4318 0.508)
			(layers "B.Cu" "B.Mask" "B.Paste")
			(net "GPU_PRSNT")
		)
		(pad "6" smd rect
			(at -0.94996 -0.649986 90)
			(size 0.4318 0.508)
			(layers "B.Cu" "B.Mask" "B.Paste")
			(net "GPU_PRSNT")
		)
	)
	(footprint ""
		(layer "B.Cu")
		(at 122.888248 -165.079934 -90)
		(property "Reference" "PC330_2"
			(at 0 0 90)
			(layer "B.SilkS")
			(hide yes)
			(effects
				(font
					(size 1.27 1.27)
				)
				(justify mirror)
			)
		)
		(property "Value" ""
			(at 0 0 90)
			(layer "B.Fab")
			(effects
				(font
					(size 1.27 1.27)
				)
				(justify mirror)
			)
		)
		(duplicate_pad_numbers_are_jumpers no)
		(fp_line
			(start -1.524 0.762)
			(end 1.524 0.762)
			(stroke
				(width 0.1524)
				(type default)
			)
			(layer "B.SilkS")
		)
		(fp_line
			(start 1.524 0.762)
			(end 1.524 -0.762)
			(stroke
				(width 0.1524)
				(type default)
			)
			(layer "B.SilkS")
		)
		(fp_line
			(start -1.524 -0.762)
			(end -1.524 0.762)
			(stroke
				(width 0.1524)
				(type default)
			)
			(layer "B.SilkS")
		)
		(fp_line
			(start 1.524 -0.762)
			(end -1.524 -0.762)
			(stroke
				(width 0.1524)
				(type default)
			)
			(layer "B.SilkS")
		)
		(fp_line
			(start -1.1049 0.724916)
			(end -1.1049 -0.724916)
			(stroke
				(width 0.1)
				(type default)
			)
			(layer "B.Fab")
		)
		(fp_line
			(start 1.1049 0.724916)
			(end -1.1049 0.724916)
			(stroke
				(width 0.1)
				(type default)
			)
			(layer "B.Fab")
		)
		(fp_line
			(start -1.1049 -0.724916)
			(end 1.1049 -0.724916)
			(stroke
				(width 0.1)
				(type default)
			)
			(layer "B.Fab")
		)
		(fp_line
			(start 1.1049 -0.724916)
			(end 1.1049 0.724916)
			(stroke
				(width 0.1)
				(type default)
			)
			(layer "B.Fab")
		)
		(pad "1" smd rect
			(at 0.889 0 270)
			(size 1.016 1.27)
			(layers "B.Cu" "B.Mask" "B.Paste")
			(net "SW_P12V_AUX_PVDDCR_SOC_P1_FLT")
		)
		(pad "2" smd rect
			(at -0.889 0 270)
			(size 1.016 1.27)
			(layers "B.Cu" "B.Mask" "B.Paste")
			(net "GND")
		)
	)
	(footprint ""
		(layer "B.Cu")
		(at 192.27292 -351.23882 90)
		(property "Reference" "PC516_2"
			(at 0 0 90)
			(layer "B.SilkS")
			(hide yes)
			(effects
				(font
					(size 1.27 1.27)
				)
				(justify mirror)
			)
		)
		(property "Value" ""
			(at 0 0 90)
			(layer "B.Fab")
			(effects
				(font
					(size 1.27 1.27)
				)
				(justify mirror)
			)
		)
		(duplicate_pad_numbers_are_jumpers no)
		(fp_line
			(start 1.524 -0.762)
			(end -1.524 -0.762)
			(stroke
				(width 0.1524)
				(type default)
			)
			(layer "B.SilkS")
		)
		(fp_line
			(start -1.524 -0.762)
			(end -1.524 0.762)
			(stroke
				(width 0.1524)
				(type default)
			)
			(layer "B.SilkS")
		)
		(fp_line
			(start 1.524 0.762)
			(end 1.524 -0.762)
			(stroke
				(width 0.1524)
				(type default)
			)
			(layer "B.SilkS")
		)
		(fp_line
			(start -1.524 0.762)
			(end 1.524 0.762)
			(stroke
				(width 0.1524)
				(type default)
			)
			(layer "B.SilkS")
		)
		(fp_line
			(start 1.1049 -0.724916)
			(end 1.1049 0.724916)
			(stroke
				(width 0.1)
				(type default)
			)
			(layer "B.Fab")
		)
		(fp_line
			(start -1.1049 -0.724916)
			(end 1.1049 -0.724916)
			(stroke
				(width 0.1)
				(type default)
			)
			(layer "B.Fab")
		)
		(fp_line
			(start 1.1049 0.724916)
			(end -1.1049 0.724916)
			(stroke
				(width 0.1)
				(type default)
			)
			(layer "B.Fab")
		)
		(fp_line
			(start -1.1049 0.724916)
			(end -1.1049 -0.724916)
			(stroke
				(width 0.1)
				(type default)
			)
			(layer "B.Fab")
		)
		(pad "1" smd rect
			(at 0.889 0 90)
			(size 1.016 1.27)
			(layers "B.Cu" "B.Mask" "B.Paste")
			(net "SW_P12V_AUX_PVDD11_S3_P1_FLT")
		)
		(pad "2" smd rect
			(at -0.889 0 90)
			(size 1.016 1.27)
			(layers "B.Cu" "B.Mask" "B.Paste")
			(net "GND")
		)
	)
)
